#ISCELL
  mstr_misc dns *
  *
#ISCELL
  pure_quanta quanta_title_block_c *
  *
#ISCELL
  standard offpage *
  page295_i121
#CELL
  pure_quanta q_res *
  page295_i122
#ISCELL
  logical_power universal_power *
  page295_i123
#ISCELL
  logical_power universal_gnd *
  page295_i124
#CELL
  pure_quanta q_cap *
  page295_i125
#ISCELL
  logical_power universal_gnd *
  page295_i128
#CELL
  pure_quanta ina230airgtr *
  page295_i129
#CELL
  pure_quanta q_res *
  page295_i130
#CELL
  pure_quanta q_res *
  page295_i131
#CELL
  pure_quanta q_res *
  page295_i132
#CELL
  pure_quanta q_cap *
  page295_i133
#CELL
  pure_quanta q_res *
  page295_i134
#CELL
  pure_quanta q_res *
  page295_i135
#CELL
  pure_quanta q_res *
  page295_i136
#ISCELL
  logical_power universal_gnd *
  page295_i137
#ISCELL
  standard offpage *
  page295_i138
#ISCELL
  standard offpage *
  page295_i139
#ISCELL
  logical_power universal_power *
  page295_i140
#CELL
  pure_quanta q_cap *
  page295_i142
#ISCELL
  logical_power universal_gnd *
  page295_i143
#ISCELL
  logical_power universal_power *
  page295_i145
#CELL
  pure_quanta q_res *
  page295_i146
#ISCELL
  logical_power universal_power *
  page295_i147
#ISCELL
  logical_power universal_power *
  page295_i148
#CELL
  pure_quanta q_res *
  page295_i149
#ISCELL
  logical_power universal_power *
  page295_i150
#CELL
  pure_quanta q_res *
  page295_i151
#CELL
  pure_quanta q_res *
  page295_i152
#CELL
  pure_quanta q_res *
  page295_i153
#CELL
  pure_quanta ina230airgtr *
  page295_i30
#CELL
  pure_quanta q_res *
  page295_i31
#ISCELL
  standard offpage *
  page295_i32
#ISCELL
  logical_power universal_power *
  page295_i33
#CELL
  pure_quanta q_cap *
  page295_i34
#CELL
  pure_quanta q_res *
  page295_i35
#ISCELL
  logical_power universal_gnd *
  page295_i36
#ISCELL
  logical_power universal_gnd *
  page295_i37
#CELL
  pure_quanta q_res *
  page295_i38
#CELL
  pure_quanta q_res *
  page295_i39
#CELL
  pure_quanta q_res *
  page295_i40
#CELL
  pure_quanta q_res *
  page295_i41
#CELL
  pure_quanta q_res *
  page295_i43
#ISCELL
  logical_power universal_gnd *
  page295_i45
#ISCELL
  standard offpage *
  page295_i46
#ISCELL
  standard offpage *
  page295_i47
#ISCELL
  logical_power universal_gnd *
  page295_i49
#CELL
  pure_quanta q_cap *
  page295_i50
#CELL
  pure_quanta q_cap *
  page295_i77
#ISCELL
  logical_power universal_power *
  page295_i79
#ISCELL
  logical_power universal_power *
  page295_i80
#ISCELL
  logical_power universal_power *
  page295_i81
#ISCELL
  logical_power universal_power *
  page295_i87
#CELL
  pure_quanta q_res *
  page295_i88
#CELL
  pure_quanta q_res *
  page295_i89
